(kicad_pcb
	(version 20260206)
	(generator "pcbnew")
	(generator_version "10.0")
	(general
		(thickness 1.6)
		(legacy_teardrops no)
	)
	(paper "A4")
	(title_block
		(title "Bryce Canyon_SCC_16316-1_OCP.brd")
		(comment 1 "Bryce Canyon / footprints 625-632 of 1561")
	)
	(layers
		(0 "F.Cu" signal "TOP")
		(4 "In1.Cu" signal "L2GND")
		(6 "In2.Cu" signal "L3")
		(8 "In3.Cu" signal "L4VCC")
		(10 "In4.Cu" signal "L5VCC")
		(12 "In5.Cu" signal "L6")
		(14 "In6.Cu" signal "L7GND")
		(2 "B.Cu" signal "BOTTOM")
		(9 "F.Adhes" user "F.Adhesive")
		(11 "B.Adhes" user "B.Adhesive")
		(13 "F.Paste" user "Package Geometry/Pastemask Top")
		(15 "B.Paste" user "Package Geometry/Pastemask Bottom")
		(5 "F.SilkS" user "Ref Des/Silkscreen Top")
		(7 "B.SilkS" user "Ref Des/Silkscreen Bottom")
		(1 "F.Mask" user "Board Geometry/Soldermask Top")
		(3 "B.Mask" user "Board Geometry/Soldermask Bottom")
		(17 "Dwgs.User" user "User.Drawings")
		(19 "Cmts.User" user "User.Comments")
		(21 "Eco1.User" user "User.Eco1")
		(23 "Eco2.User" user "User.Eco2")
		(25 "Edge.Cuts" user "Board Geometry/Outline")
		(27 "Margin" user)
		(31 "F.CrtYd" user "Package Geometry/Place Bound Top")
		(29 "B.CrtYd" user "Package Geometry/Place Bound Bottom")
		(35 "F.Fab" user "Ref Des/Assembly Top")
		(33 "B.Fab" user "Ref Des/Assembly Bottom")
	)
	(footprint ""
		(layer "F.Cu")
		(at 58.5978 -72.6948)
		(property "Reference" "R420"
			(at 0 0 0)
			(layer "F.SilkS")
			(hide yes)
			(effects
				(font
					(size 1.27 1.27)
				)
			)
		)
		(property "Value" "200KR2F-L-GP"
			(at 0.064008 -3.993896 0)
			(unlocked yes)
			(layer "F.Fab")
			(hide yes)
			(effects
				(font
					(size 1.016 1.016)
					(thickness 0.1524)
				)
			)
		)
		(property "Device Type" "R402H16"
			(at 0.064008 -5.517896 0)
			(unlocked yes)
			(layer "F.Fab")
			(hide yes)
			(effects
				(font
					(size 1.016 1.016)
					(thickness 0.1524)
				)
			)
		)
		(duplicate_pad_numbers_are_jumpers no)
		(fp_line
			(start -0.508 -0.9398)
			(end -0.508 0.9398)
			(stroke
				(width 0.1524)
				(type default)
			)
			(layer "F.SilkS")
		)
		(fp_line
			(start 0.508 -0.9398)
			(end -0.508 -0.9398)
			(stroke
				(width 0.1524)
				(type default)
			)
			(layer "F.SilkS")
		)
		(fp_rect
			(start -0.508 0.9398)
			(end 0.508 -0.9398)
			(stroke
				(width 0)
				(type default)
			)
			(fill no)
			(layer "F.CrtYd")
		)
		(fp_rect
			(start -0.508 0.9398)
			(end 0.508 -0.9398)
			(stroke
				(width 0)
				(type default)
			)
			(fill no)
			(layer "F.Fab")
		)
		(pad "1" smd custom
			(at 0 -0.4445)
			(size 0.1397 0.1397)
			(layers "F.Cu" "F.Mask" "F.Paste")
			(net "VREF4")
			(options
				(clearance outline)
				(anchor circle)
			)
			(primitives
				(gr_poly
					(pts
						(arc
							(start -0.1778 -0.2794)
							(mid -0.249642 -0.249642)
							(end -0.2794 -0.1778)
						)
						(arc
							(start -0.2794 0.1778)
							(mid -0.249642 0.249642)
							(end -0.1778 0.2794)
						)
						(arc
							(start 0.1778 0.2794)
							(mid 0.249642 0.249642)
							(end 0.2794 0.1778)
						)
						(arc
							(start 0.2794 -0.1778)
							(mid 0.249642 -0.249642)
							(end 0.1778 -0.2794)
						)
					)
					(width 0)
					(fill yes)
				)
			)
		)
		(pad "2" smd custom
			(at 0 0.4445)
			(size 0.1397 0.1397)
			(layers "F.Cu" "F.Mask" "F.Paste")
			(net "P3V3")
			(options
				(clearance outline)
				(anchor circle)
			)
			(primitives
				(gr_poly
					(pts
						(arc
							(start -0.1778 -0.2794)
							(mid -0.249642 -0.249642)
							(end -0.2794 -0.1778)
						)
						(arc
							(start -0.2794 0.1778)
							(mid -0.249642 0.249642)
							(end -0.1778 0.2794)
						)
						(arc
							(start 0.1778 0.2794)
							(mid 0.249642 0.249642)
							(end 0.2794 0.1778)
						)
						(arc
							(start 0.2794 -0.1778)
							(mid 0.249642 -0.249642)
							(end 0.1778 -0.2794)
						)
					)
					(width 0)
					(fill yes)
				)
			)
		)
	)
	(footprint ""
		(layer "F.Cu")
		(at 191.850772 -47.562262 -90)
		(property "Reference" "R216"
			(at 0 0 270)
			(layer "F.SilkS")
			(hide yes)
			(effects
				(font
					(size 1.27 1.27)
				)
			)
		)
		(property "Value" "10KR2F-2-GP"
			(at 0.064008 -3.993896 270)
			(unlocked yes)
			(layer "F.Fab")
			(hide yes)
			(effects
				(font
					(size 1.016 1.016)
					(thickness 0.1524)
				)
			)
		)
		(property "Device Type" "R402H16"
			(at 0.064008 -5.517896 270)
			(unlocked yes)
			(layer "F.Fab")
			(hide yes)
			(effects
				(font
					(size 1.016 1.016)
					(thickness 0.1524)
				)
			)
		)
		(duplicate_pad_numbers_are_jumpers no)
		(fp_line
			(start -0.508 -0.9398)
			(end -0.508 0.9398)
			(stroke
				(width 0.1524)
				(type default)
			)
			(layer "F.SilkS")
		)
		(fp_line
			(start 0.508 -0.9398)
			(end -0.508 -0.9398)
			(stroke
				(width 0.1524)
				(type default)
			)
			(layer "F.SilkS")
		)
		(fp_rect
			(start -0.508 0.9398)
			(end 0.508 -0.9398)
			(stroke
				(width 0)
				(type default)
			)
			(fill no)
			(layer "F.CrtYd")
		)
		(fp_rect
			(start -0.508 0.9398)
			(end 0.508 -0.9398)
			(stroke
				(width 0)
				(type default)
			)
			(fill no)
			(layer "F.Fab")
		)
		(pad "1" smd custom
			(at 0 -0.4445 270)
			(size 0.1397 0.1397)
			(layers "F.Cu" "F.Mask" "F.Paste")
			(net "P1V8_C")
			(options
				(clearance outline)
				(anchor circle)
			)
			(primitives
				(gr_poly
					(pts
						(arc
							(start -0.1778 -0.2794)
							(mid -0.249642 -0.249642)
							(end -0.2794 -0.1778)
						)
						(arc
							(start -0.2794 0.1778)
							(mid -0.249642 0.249642)
							(end -0.1778 0.2794)
						)
						(arc
							(start 0.1778 0.2794)
							(mid 0.249642 0.249642)
							(end 0.2794 0.1778)
						)
						(arc
							(start 0.2794 -0.1778)
							(mid 0.249642 -0.249642)
							(end 0.1778 -0.2794)
						)
					)
					(width 0)
					(fill yes)
				)
			)
		)
		(pad "2" smd custom
			(at 0 0.4445 270)
			(size 0.1397 0.1397)
			(layers "F.Cu" "F.Mask" "F.Paste")
			(net "XM_ADDR_22")
			(options
				(clearance outline)
				(anchor circle)
			)
			(primitives
				(gr_poly
					(pts
						(arc
							(start -0.1778 -0.2794)
							(mid -0.249642 -0.249642)
							(end -0.2794 -0.1778)
						)
						(arc
							(start -0.2794 0.1778)
							(mid -0.249642 0.249642)
							(end -0.1778 0.2794)
						)
						(arc
							(start 0.1778 0.2794)
							(mid 0.249642 0.249642)
							(end 0.2794 0.1778)
						)
						(arc
							(start 0.2794 -0.1778)
							(mid 0.249642 -0.249642)
							(end 0.1778 -0.2794)
						)
					)
					(width 0)
					(fill yes)
				)
			)
		)
	)
	(footprint ""
		(layer "F.Cu")
		(at 87.122 -77.216 180)
		(property "Reference" "R97"
			(at 0 0 180)
			(layer "F.SilkS")
			(hide yes)
			(effects
				(font
					(size 1.27 1.27)
				)
			)
		)
		(property "Value" "10KR2F-2-GP"
			(at 0.064008 -3.993896 180)
			(unlocked yes)
			(layer "F.Fab")
			(hide yes)
			(effects
				(font
					(size 1.016 1.016)
					(thickness 0.1524)
				)
			)
		)
		(property "Device Type" "R402H16"
			(at 0.064008 -5.517896 180)
			(unlocked yes)
			(layer "F.Fab")
			(hide yes)
			(effects
				(font
					(size 1.016 1.016)
					(thickness 0.1524)
				)
			)
		)
		(duplicate_pad_numbers_are_jumpers no)
		(fp_line
			(start 0.508 -0.9398)
			(end -0.508 -0.9398)
			(stroke
				(width 0.1524)
				(type default)
			)
			(layer "F.SilkS")
		)
		(fp_line
			(start -0.508 -0.9398)
			(end -0.508 0.9398)
			(stroke
				(width 0.1524)
				(type default)
			)
			(layer "F.SilkS")
		)
		(fp_rect
			(start -0.508 0.9398)
			(end 0.508 -0.9398)
			(stroke
				(width 0)
				(type default)
			)
			(fill no)
			(layer "F.CrtYd")
		)
		(fp_rect
			(start -0.508 0.9398)
			(end 0.508 -0.9398)
			(stroke
				(width 0)
				(type default)
			)
			(fill no)
			(layer "F.Fab")
		)
		(pad "1" smd custom
			(at 0 -0.4445 180)
			(size 0.1397 0.1397)
			(layers "F.Cu" "F.Mask" "F.Paste")
			(net "P1V8_E")
			(options
				(clearance outline)
				(anchor circle)
			)
			(primitives
				(gr_poly
					(pts
						(arc
							(start -0.1778 -0.2794)
							(mid -0.249642 -0.249642)
							(end -0.2794 -0.1778)
						)
						(arc
							(start -0.2794 0.1778)
							(mid -0.249642 0.249642)
							(end -0.1778 0.2794)
						)
						(arc
							(start 0.1778 0.2794)
							(mid 0.249642 0.249642)
							(end 0.2794 0.1778)
						)
						(arc
							(start 0.2794 -0.1778)
							(mid 0.249642 -0.249642)
							(end 0.1778 -0.2794)
						)
					)
					(width 0)
					(fill yes)
				)
			)
		)
		(pad "2" smd custom
			(at 0 0.4445 180)
			(size 0.1397 0.1397)
			(layers "F.Cu" "F.Mask" "F.Paste")
			(net "EXP_BLINK_OUT")
			(options
				(clearance outline)
				(anchor circle)
			)
			(primitives
				(gr_poly
					(pts
						(arc
							(start -0.1778 -0.2794)
							(mid -0.249642 -0.249642)
							(end -0.2794 -0.1778)
						)
						(arc
							(start -0.2794 0.1778)
							(mid -0.249642 0.249642)
							(end -0.1778 0.2794)
						)
						(arc
							(start 0.1778 0.2794)
							(mid 0.249642 0.249642)
							(end 0.2794 0.1778)
						)
						(arc
							(start 0.2794 -0.1778)
							(mid 0.249642 -0.249642)
							(end 0.1778 -0.2794)
						)
					)
					(width 0)
					(fill yes)
				)
			)
		)
	)
	(footprint ""
		(layer "F.Cu")
		(at 130.556 -89.7382)
		(property "Reference" "R117"
			(at 0 0 0)
			(layer "F.SilkS")
			(hide yes)
			(effects
				(font
					(size 1.27 1.27)
				)
			)
		)
		(property "Value" "4K75R2F-1-GP"
			(at 0.064008 -3.993896 0)
			(unlocked yes)
			(layer "F.Fab")
			(hide yes)
			(effects
				(font
					(size 1.016 1.016)
					(thickness 0.1524)
				)
			)
		)
		(property "Device Type" "R402H16"
			(at 0.064008 -5.517896 0)
			(unlocked yes)
			(layer "F.Fab")
			(hide yes)
			(effects
				(font
					(size 1.016 1.016)
					(thickness 0.1524)
				)
			)
		)
		(duplicate_pad_numbers_are_jumpers no)
		(fp_line
			(start -0.508 -0.9398)
			(end -0.508 0.9398)
			(stroke
				(width 0.1524)
				(type default)
			)
			(layer "F.SilkS")
		)
		(fp_line
			(start 0.508 -0.9398)
			(end -0.508 -0.9398)
			(stroke
				(width 0.1524)
				(type default)
			)
			(layer "F.SilkS")
		)
		(fp_rect
			(start -0.508 0.9398)
			(end 0.508 -0.9398)
			(stroke
				(width 0)
				(type default)
			)
			(fill no)
			(layer "F.CrtYd")
		)
		(fp_rect
			(start -0.508 0.9398)
			(end 0.508 -0.9398)
			(stroke
				(width 0)
				(type default)
			)
			(fill no)
			(layer "F.Fab")
		)
		(pad "1" smd custom
			(at 0 -0.4445)
			(size 0.1397 0.1397)
			(layers "F.Cu" "F.Mask" "F.Paste")
			(net "P1V8_E")
			(options
				(clearance outline)
				(anchor circle)
			)
			(primitives
				(gr_poly
					(pts
						(arc
							(start -0.1778 -0.2794)
							(mid -0.249642 -0.249642)
							(end -0.2794 -0.1778)
						)
						(arc
							(start -0.2794 0.1778)
							(mid -0.249642 0.249642)
							(end -0.1778 0.2794)
						)
						(arc
							(start 0.1778 0.2794)
							(mid 0.249642 0.249642)
							(end 0.2794 0.1778)
						)
						(arc
							(start 0.2794 -0.1778)
							(mid 0.249642 -0.249642)
							(end 0.1778 -0.2794)
						)
					)
					(width 0)
					(fill yes)
				)
			)
		)
		(pad "2" smd custom
			(at 0 0.4445)
			(size 0.1397 0.1397)
			(layers "F.Cu" "F.Mask" "F.Paste")
			(net "SAS_SMART_RX")
			(options
				(clearance outline)
				(anchor circle)
			)
			(primitives
				(gr_poly
					(pts
						(arc
							(start -0.1778 -0.2794)
							(mid -0.249642 -0.249642)
							(end -0.2794 -0.1778)
						)
						(arc
							(start -0.2794 0.1778)
							(mid -0.249642 0.249642)
							(end -0.1778 0.2794)
						)
						(arc
							(start 0.1778 0.2794)
							(mid 0.249642 0.249642)
							(end 0.2794 0.1778)
						)
						(arc
							(start 0.2794 -0.1778)
							(mid 0.249642 -0.249642)
							(end 0.1778 -0.2794)
						)
					)
					(width 0)
					(fill yes)
				)
			)
		)
	)
	(footprint ""
		(layer "F.Cu")
		(at 124.682758 -46.430438 90)
		(property "Reference" "VIA9"
			(at 0 0 90)
			(layer "F.SilkS")
			(hide yes)
			(effects
				(font
					(size 1.27 1.27)
				)
			)
		)
		(property "Value" "100OHM-8L-1D6MM-L13-GP"
			(at 3.2893 0.0508 90)
			(unlocked yes)
			(layer "F.Fab")
			(hide yes)
			(effects
				(font
					(size 1.016 1.016)
					(thickness 0.1524)
				)
			)
		)
		(property "Device Type" "VIA-PCIE-4P-409091"
			(at 3.2893 -1.4732 90)
			(unlocked yes)
			(layer "F.Fab")
			(hide yes)
			(effects
				(font
					(size 1.016 1.016)
					(thickness 0.1524)
				)
			)
		)
		(duplicate_pad_numbers_are_jumpers no)
		(fp_rect
			(start -2.0447 0.4572)
			(end 2.0447 -0.4572)
			(stroke
				(width 0)
				(type default)
			)
			(fill no)
			(layer "F.CrtYd")
		)
		(fp_rect
			(start -2.0447 0.4572)
			(end 2.0447 -0.4572)
			(stroke
				(width 0)
				(type default)
			)
			(fill no)
			(layer "F.Fab")
		)
		(pad "1" thru_hole circle
			(at -1.5875 0 90)
			(size 0.508 0.508)
			(drill 0.254)
			(layers "*.Cu" "*.Mask")
			(remove_unused_layers no)
			(net "GND")
			(clearance 0.2032)
			(thermal_gap 0.2032)
		)
		(pad "2" thru_hole circle
			(at -0.5715 0 90)
			(size 0.508 0.508)
			(drill 0.254)
			(layers "*.Cu" "*.Mask")
			(remove_unused_layers no)
			(net "PHY_IOC_TO_SCC_C_40_DP")
			(clearance 0.2032)
			(thermal_gap 0.2032)
		)
		(pad "3" thru_hole circle
			(at 0.5715 0 90)
			(size 0.508 0.508)
			(drill 0.254)
			(layers "*.Cu" "*.Mask")
			(remove_unused_layers no)
			(net "PHY_IOC_TO_SCC_C_40_DN")
			(clearance 0.2032)
			(thermal_gap 0.2032)
		)
		(pad "4" thru_hole circle
			(at 1.5875 0 90)
			(size 0.508 0.508)
			(drill 0.254)
			(layers "*.Cu" "*.Mask")
			(remove_unused_layers no)
			(net "GND")
			(clearance 0.2032)
			(thermal_gap 0.2032)
		)
	)
	(footprint ""
		(layer "F.Cu")
		(at 60.6806 -72.6948 180)
		(property "Reference" "R418"
			(at 0 0 180)
			(layer "F.SilkS")
			(hide yes)
			(effects
				(font
					(size 1.27 1.27)
				)
			)
		)
		(property "Value" "1KR2F-3-GP"
			(at 0.064008 -3.993896 180)
			(unlocked yes)
			(layer "F.Fab")
			(hide yes)
			(effects
				(font
					(size 1.016 1.016)
					(thickness 0.1524)
				)
			)
		)
		(property "Device Type" "R402H16"
			(at 0.064008 -5.517896 180)
			(unlocked yes)
			(layer "F.Fab")
			(hide yes)
			(effects
				(font
					(size 1.016 1.016)
					(thickness 0.1524)
				)
			)
		)
		(duplicate_pad_numbers_are_jumpers no)
		(fp_line
			(start 0.508 -0.9398)
			(end -0.508 -0.9398)
			(stroke
				(width 0.1524)
				(type default)
			)
			(layer "F.SilkS")
		)
		(fp_line
			(start -0.508 -0.9398)
			(end -0.508 0.9398)
			(stroke
				(width 0.1524)
				(type default)
			)
			(layer "F.SilkS")
		)
		(fp_rect
			(start -0.508 0.9398)
			(end 0.508 -0.9398)
			(stroke
				(width 0)
				(type default)
			)
			(fill no)
			(layer "F.CrtYd")
		)
		(fp_rect
			(start -0.508 0.9398)
			(end 0.508 -0.9398)
			(stroke
				(width 0)
				(type default)
			)
			(fill no)
			(layer "F.Fab")
		)
		(pad "1" smd custom
			(at 0 -0.4445 180)
			(size 0.1397 0.1397)
			(layers "F.Cu" "F.Mask" "F.Paste")
			(net "P3V3")
			(options
				(clearance outline)
				(anchor circle)
			)
			(primitives
				(gr_poly
					(pts
						(arc
							(start -0.1778 -0.2794)
							(mid -0.249642 -0.249642)
							(end -0.2794 -0.1778)
						)
						(arc
							(start -0.2794 0.1778)
							(mid -0.249642 0.249642)
							(end -0.1778 0.2794)
						)
						(arc
							(start 0.1778 0.2794)
							(mid 0.249642 0.249642)
							(end 0.2794 0.1778)
						)
						(arc
							(start 0.2794 -0.1778)
							(mid 0.249642 -0.249642)
							(end 0.1778 -0.2794)
						)
					)
					(width 0)
					(fill yes)
				)
			)
		)
		(pad "2" smd custom
			(at 0 0.4445 180)
			(size 0.1397 0.1397)
			(layers "F.Cu" "F.Mask" "F.Paste")
			(net "I2C_DRIVE_INS_SDA5")
			(options
				(clearance outline)
				(anchor circle)
			)
			(primitives
				(gr_poly
					(pts
						(arc
							(start -0.1778 -0.2794)
							(mid -0.249642 -0.249642)
							(end -0.2794 -0.1778)
						)
						(arc
							(start -0.2794 0.1778)
							(mid -0.249642 0.249642)
							(end -0.1778 0.2794)
						)
						(arc
							(start 0.1778 0.2794)
							(mid 0.249642 0.249642)
							(end 0.2794 0.1778)
						)
						(arc
							(start 0.2794 -0.1778)
							(mid 0.249642 -0.249642)
							(end 0.1778 -0.2794)
						)
					)
					(width 0)
					(fill yes)
				)
			)
		)
	)
	(footprint ""
		(layer "F.Cu")
		(at 41.21658 -26.49474 90)
		(property "Reference" "R406"
			(at 0 0 90)
			(layer "F.SilkS")
			(hide yes)
			(effects
				(font
					(size 1.27 1.27)
				)
			)
		)
		(property "Value" "0R2J-2-GP"
			(at 0.064008 -3.993896 90)
			(unlocked yes)
			(layer "F.Fab")
			(hide yes)
			(effects
				(font
					(size 1.016 1.016)
					(thickness 0.1524)
				)
			)
		)
		(property "Device Type" "R402H16"
			(at 0.064008 -5.517896 90)
			(unlocked yes)
			(layer "F.Fab")
			(hide yes)
			(effects
				(font
					(size 1.016 1.016)
					(thickness 0.1524)
				)
			)
		)
		(duplicate_pad_numbers_are_jumpers no)
		(fp_line
			(start 0.508 -0.9398)
			(end -0.508 -0.9398)
			(stroke
				(width 0.1524)
				(type default)
			)
			(layer "F.SilkS")
		)
		(fp_line
			(start -0.508 -0.9398)
			(end -0.508 0.9398)
			(stroke
				(width 0.1524)
				(type default)
			)
			(layer "F.SilkS")
		)
		(fp_rect
			(start -0.508 0.9398)
			(end 0.508 -0.9398)
			(stroke
				(width 0)
				(type default)
			)
			(fill no)
			(layer "F.CrtYd")
		)
		(fp_rect
			(start -0.508 0.9398)
			(end 0.508 -0.9398)
			(stroke
				(width 0)
				(type default)
			)
			(fill no)
			(layer "F.Fab")
		)
		(pad "1" smd custom
			(at 0 -0.4445 90)
			(size 0.1397 0.1397)
			(layers "F.Cu" "F.Mask" "F.Paste")
			(net "P0V9_PG")
			(options
				(clearance outline)
				(anchor circle)
			)
			(primitives
				(gr_poly
					(pts
						(arc
							(start -0.1778 -0.2794)
							(mid -0.249642 -0.249642)
							(end -0.2794 -0.1778)
						)
						(arc
							(start -0.2794 0.1778)
							(mid -0.249642 0.249642)
							(end -0.1778 0.2794)
						)
						(arc
							(start 0.1778 0.2794)
							(mid 0.249642 0.249642)
							(end 0.2794 0.1778)
						)
						(arc
							(start 0.2794 -0.1778)
							(mid 0.249642 -0.249642)
							(end 0.1778 -0.2794)
						)
					)
					(width 0)
					(fill yes)
				)
			)
		)
		(pad "2" smd custom
			(at 0 0.4445 90)
			(size 0.1397 0.1397)
			(layers "F.Cu" "F.Mask" "F.Paste")
			(net "SCC_FULL_PGOOD")
			(options
				(clearance outline)
				(anchor circle)
			)
			(primitives
				(gr_poly
					(pts
						(arc
							(start -0.1778 -0.2794)
							(mid -0.249642 -0.249642)
							(end -0.2794 -0.1778)
						)
						(arc
							(start -0.2794 0.1778)
							(mid -0.249642 0.249642)
							(end -0.1778 0.2794)
						)
						(arc
							(start 0.1778 0.2794)
							(mid 0.249642 0.249642)
							(end 0.2794 0.1778)
						)
						(arc
							(start 0.2794 -0.1778)
							(mid 0.249642 -0.249642)
							(end 0.1778 -0.2794)
						)
					)
					(width 0)
					(fill yes)
				)
			)
		)
	)
	(footprint ""
		(layer "F.Cu")
		(at 193.929 -29.21 -90)
		(property "Reference" "TP64"
			(at 0 0 270)
			(layer "F.SilkS")
			(hide yes)
			(effects
				(font
					(size 1.27 1.27)
				)
			)
		)
		(property "Value" "TPAD28-2-GP"
			(at -0.0127 -1.6637 270)
			(unlocked yes)
			(layer "F.Fab")
			(hide yes)
			(effects
				(font
					(size 1.016 1.016)
					(thickness 0.1524)
				)
			)
		)
		(property "Device Type" "TPAD28"
			(at -0.0127 -3.1877 270)
			(unlocked yes)
			(layer "F.Fab")
			(hide yes)
			(effects
				(font
					(size 1.016 1.016)
					(thickness 0.1524)
				)
			)
		)
		(duplicate_pad_numbers_are_jumpers no)
		(fp_poly
			(pts
				(arc
					(start 0 -0.3556)
					(mid 0 0.3556)
					(end 0 -0.3556)
				)
			)
			(stroke
				(width 0)
				(type default)
			)
			(fill no)
			(layer "F.CrtYd")
		)
		(fp_poly
			(pts
				(arc
					(start 0 -0.6096)
					(mid 0 0.6096)
					(end 0 -0.6096)
				)
			)
			(stroke
				(width 0)
				(type default)
			)
			(fill no)
			(layer "F.Fab")
		)
		(pad "1" smd circle
			(at 0 0 270)
			(size 0.7112 0.7112)
			(layers "F.Cu" "F.Mask" "F.Paste")
			(net "IOC_GPIO_11")
		)
	)
)
